FILE_TYPE = CONNECTIVITY;
{Allegro Design Entry HDL 17.4-2019 S026 (4007227) 1/17/2022}
"PAGE_NUMBER" = 341;
0"NC";
1"GND\g";
2"GND\g";
3"GND\g";
4"P3V3_OCP_V3_2\g";
5"P5E_CPU1_G1_RX_DP<15:0>";
6"P5E_CPU1_G1_RX_DN<15:0>";
7"P5E_CPU1_G1_TX_C_DN<15:0>";
8"P5E_CPU1_G1_TX_C_DP<15:0>";
9"NCSI_OCP_V3_2_CRS_DV";
10"CLK_100M_CPU1_CLK04_DP";
11"CLK_100M_CPU1_CLK04_DN";
12"NCSI_OCP_V3_2_TXD0";
13"NCSI_OCP_V3_2_TXD1";
14"NCSI_OCP_V3_2_TX_EN";
15"OCP_V3_2_ID1";
16"OCP_V3_2_ISO2_RBT_ARB_OUT";
17"FM_OCP_V3_2_PWR_GOOD";
18"GND\g";
19"CLK_100M_CPU1_CLK05_DN";
20"CLK_100M_CPU1_CLK05_DP";
21"CLK_50M_NCSI_OCP_V3_2_ISO";
22"SMB_OCP_V3_2_3V3AUX_BUF_R_SCL";
23"SMB_OCP_V3_2_3V3AUX_BUF_SCL";
24"OCP_V3_2_PRSNTA_R_N";
25"RST_SMB_OCP_V3_2_N";
26"RST_PERST1_OCP_V3_2_N";
27"OCP_V3_2_PRSNT2_R_N";
28"CLK_100M_CPU1_CLK03_DN";
29"SMB_OCP_V3_2_3V3AUX_BUF_SDA";
30"P5E_CPU1_G1_RX_DN<0>";
31"CLK_100M_CPU1_CLK03_DP";
32"P3V3_OCP_V3_2\g";
33"P12V_OCP_V3_2_R\g";
34"GND\g";
35"GND\g";
36"P3V3_OCP_V3_2\g";
37"GND\g";
38"GND\g";
39"GND\g";
40"P3V3_OCP_V3_2\g";
41"P12V_OCP_V3_2_R\g";
42"SGPIO_OCP_V3_2_DATAIN";
43"SGPIO_OCP_V3_2_LD_N";
44"OCP_V3_2_MAIN_PWR_EN_R";
45"OCP_V3_2_BIF1_R_N";
46"OCP_V3_2_MAIN_PWR_EN";
47"OCP_V3_2_ISO_BIF0_EN";
48"OCP_V3_2_ISO_BIF1_EN";
49"OCP_V3_2_ISO_BIF2_EN";
50"RST_PERST0_OCP_V3_2_N";
51"OCP_V3_2_BIF0_R_N";
52"OCP_V3_2_AUX_PWR_EN_R";
53"CLK_100M_CPU1_CLK02_DN";
54"CLK_100M_CPU1_CLK02_DP";
55"RST_PERST2_OCP_V3_2_N";
56"P5E_CPU1_G1_RX_DN<1>";
57"P5E_CPU1_G1_RX_DP<0>";
58"OCP_V3_2_PRSNT1_R_N";
59"P5E_CPU1_G1_RX_DN<7>";
60"P5E_CPU1_G1_RX_DP<7>";
61"P5E_CPU1_G1_RX_DP<8>";
62"P5E_CPU1_G1_RX_DN<8>";
63"USB2_CPU0_P10_DN";
64"USB2_CPU0_P10_DP";
65"OCP_V3_2_PWRBRK_N";
66"USB2_P10_DN";
67"USB2_P10_DP";
68"SGPIO_OCP_V3_2_LD_N";
69"OCP_V3_2_PRSNT3_R_N";
70"TP_OCP_V3_2_B69";
71"TP_OCP_V3_2_B68";
72"OCP_V3_2_PRSNT0_R_N";
73"OCP_V3_2_AUX_PWR_EN"CDS_PHYS_NET_NAME"OCP_V3_2_AUX_PWR_EN";
74"IRQ_LVC3_OCP_V3_2_WAKE_N";
75"P5E_CPU1_G1_TX_C_DP<0>";
76"P5E_CPU1_G1_TX_C_DP<2>";
77"P5E_CPU1_G1_TX_C_DN<1>";
78"P5E_CPU1_G1_TX_C_DP<1>";
79"P5E_CPU1_G1_TX_C_DN<0>";
80"SGPIO_OCP_V3_2_DATAIN";
81"SGPIO_OCP_V3_2_DATAOUT";
82"SGPIO_OCP_V3_2_CLK";
83"OCP_V3_2_ID0";
84"OCP_V3_2_ID1";
85"OCP_V3_2_MAIN_PWR_EN"CDS_PHYS_NET_NAME"OCP_V3_2_MAIN_PWR_EN";
86"P5E_CPU1_G1_TX_C_DN<15>";
87"P5E_CPU1_G1_TX_C_DP<15>";
88"P5E_CPU1_G1_TX_C_DN<14>";
89"P5E_CPU1_G1_TX_C_DP<14>";
90"P5E_CPU1_G1_TX_C_DN<13>";
91"P5E_CPU1_G1_TX_C_DP<13>";
92"P5E_CPU1_G1_TX_C_DN<12>";
93"P5E_CPU1_G1_RX_DN<14>";
94"P5E_CPU1_G1_RX_DP<13>";
95"P5E_CPU1_G1_RX_DN<13>";
96"P5E_CPU1_G1_RX_DP<11>";
97"P5E_CPU1_G1_RX_DP<10>";
98"P5E_CPU1_G1_RX_DN<10>";
99"P5E_CPU1_G1_RX_DP<9>";
100"P5E_CPU1_G1_RX_DN<9>";
101"P5E_CPU1_G1_RX_DP<6>";
102"P5E_CPU1_G1_RX_DN<6>";
103"P5E_CPU1_G1_RX_DP<5>";
104"P5E_CPU1_G1_RX_DN<5>";
105"P5E_CPU1_G1_RX_DP<4>";
106"P5E_CPU1_G1_RX_DN<4>";
107"P5E_CPU1_G1_RX_DP<3>";
108"P5E_CPU1_G1_RX_DP<2>";
109"P5E_CPU1_G1_RX_DN<2>";
110"P5E_CPU1_G1_RX_DP<1>";
111"RST_PERST3_OCP_V3_2_N";
112"P5E_CPU1_G1_TX_C_DP<12>";
113"P5E_CPU1_G1_TX_C_DN<11>";
114"P5E_CPU1_G1_TX_C_DP<11>";
115"P5E_CPU1_G1_TX_C_DN<10>";
116"P5E_CPU1_G1_TX_C_DP<10>";
117"P5E_CPU1_G1_TX_C_DN<9>";
118"P5E_CPU1_G1_TX_C_DP<9>";
119"P5E_CPU1_G1_TX_C_DN<8>";
120"P5E_CPU1_G1_TX_C_DP<8>";
121"P5E_CPU1_G1_TX_C_DN<7>";
122"P5E_CPU1_G1_TX_C_DP<7>";
123"P5E_CPU1_G1_TX_C_DN<6>";
124"P5E_CPU1_G1_TX_C_DP<6>";
125"P5E_CPU1_G1_TX_C_DN<5>";
126"P5E_CPU1_G1_TX_C_DP<5>";
127"P5E_CPU1_G1_TX_C_DN<4>";
128"P5E_CPU1_G1_TX_C_DP<4>";
129"P5E_CPU1_G1_TX_C_DN<3>";
130"P5E_CPU1_G1_TX_C_DP<3>";
131"P5E_CPU1_G1_TX_C_DN<2>";
132"SGPIO_OCP_V3_2_DATAOUT";
133"P5E_CPU1_G1_RX_DN<3>";
134"FM_OCP_V3_2_PWR_GOOD"CDS_PHYS_NET_NAME"FM_OCP_V3_2_PWR_GOOD";
135"P5E_CPU1_G1_RX_DN<15>";
136"P5E_CPU1_G1_RX_DN<11>";
137"P5E_CPU1_G1_RX_DP<15>";
138"P5E_CPU1_G1_RX_DN<12>";
139"OCP_V3_2_ISO1_RBT_ARB_IN";
140"P5E_CPU1_G1_RX_DP<14>";
141"P5E_CPU1_G1_RX_DP<12>";
142"OCP_V3_2_AUX_PWR_EN";
143"SGPIO_OCP_V3_2_CLK";
144"OCP_V3_2_ID0";
145"NCSI_OCP_V3_2_RXD1";
146"NCSI_OCP_V3_2_RXD0";
147"OCP_V3_2_BIF2_R_N";
148"SMB_OCP_V3_2_3V3AUX_BUF_R_SDA";
%"UNIVERSAL_GND"
"1","(275,-450)","0","pure_quanta_power","I1";
;
ROOM"IO_SLOT"
CDS_LIB"pure_quanta_power"
HDL_POWER"GND";
"A"1;
%"Q_RES"
"1","(3650,-100)","0","pure_quanta","I10";
;
LOCATION"R3173"
$SEC"1"
CDS_SEC"1"
MATERIAL"CHIP"
WATTAGE"1/16W"
TOLERANCE"1%"
VALUE"1K"
PACK_TYPE"0402LF"
CDS_LIB"pure_quanta"
PART_NUMBER"CS21002FB06";
"B"
$PN"2"32;
"A"
$PN"1"68;
%"UNIVERSAL_GND"
"1","(5300,175)","0","pure_quanta_power","I100";
;
CDS_LIB"pure_quanta_power"
HDL_POWER"GND";
"A"18;
%"TAP"
"1","(5600,875)","0","standard","I101";
;
CDS_LIB"standard"
BODY_TYPE"PLUMBING"
HDL_TAP"TRUE";
"B \NAC \NWC"5;
"S \NAC"
BN"15"137;
%"UNIVERSAL_POWER"
"1","(5700,50)","0","pure_quanta_power","I102";
;
HDL_POWER"P12V_OCP_V3_2_R"
CDS_LIB"pure_quanta_power";
"A"41;
%"TAP"
"1","(5750,925)","0","standard","I103";
;
CDS_LIB"standard"
BODY_TYPE"PLUMBING"
HDL_TAP"TRUE";
"B \NAC \NWC"6;
"S \NAC"
BN"15"135;
%"TAP"
"1","(5600,1025)","0","standard","I104";
;
CDS_LIB"standard"
BODY_TYPE"PLUMBING"
HDL_TAP"TRUE";
"B \NAC \NWC"5;
"S \NAC"
BN"14"140;
%"TAP"
"1","(5600,1175)","0","standard","I105";
;
CDS_LIB"standard"
BODY_TYPE"PLUMBING"
HDL_TAP"TRUE";
"B \NAC \NWC"5;
"S \NAC"
BN"13"94;
%"TAP"
"1","(5600,1475)","0","standard","I106";
;
CDS_LIB"standard"
BODY_TYPE"PLUMBING"
HDL_TAP"TRUE";
"B \NAC \NWC"5;
"S \NAC"
BN"11"96;
%"TAP"
"1","(5600,1325)","0","standard","I107";
;
CDS_LIB"standard"
BODY_TYPE"PLUMBING"
HDL_TAP"TRUE";
"B \NAC \NWC"5;
"S \NAC"
BN"12"141;
%"TAP"
"1","(5600,1625)","0","standard","I108";
;
CDS_LIB"standard"
BODY_TYPE"PLUMBING"
HDL_TAP"TRUE";
"B \NAC \NWC"5;
"S \NAC"
BN"10"97;
%"TAP"
"1","(5600,1775)","0","standard","I109";
;
CDS_LIB"standard"
BODY_TYPE"PLUMBING"
HDL_TAP"TRUE";
"B \NAC \NWC"5;
"S \NAC"
BN"9"99;
%"Q_RES"
"1","(3675,-625)","0","pure_quanta","I11";
;
LOCATION"R3175"
$SEC"1"
CDS_SEC"1"
TOLERANCE"1%"
VALUE"10K"
MATERIAL"CHIP"
WATTAGE"1/16W"
PACK_TYPE"0402LF"
CDS_LIB"pure_quanta"
PART_NUMBER"CS31002FB08";
"B"
$PN"2"39;
"A"
$PN"1"81;
%"TAP"
"1","(5600,1925)","0","standard","I110";
;
CDS_LIB"standard"
BODY_TYPE"PLUMBING"
HDL_TAP"TRUE";
"B \NAC \NWC"5;
"S \NAC"
BN"8"61;
%"TAP"
"1","(5750,1225)","0","standard","I111";
;
CDS_LIB"standard"
BODY_TYPE"PLUMBING"
HDL_TAP"TRUE";
"B \NAC \NWC"6;
"S \NAC"
BN"13"95;
%"TAP"
"1","(5750,1075)","0","standard","I112";
;
CDS_LIB"standard"
BODY_TYPE"PLUMBING"
HDL_TAP"TRUE";
"B \NAC \NWC"6;
"S \NAC"
BN"14"93;
%"TAP"
"1","(5750,1375)","0","standard","I113";
;
CDS_LIB"standard"
BODY_TYPE"PLUMBING"
HDL_TAP"TRUE";
"B \NAC \NWC"6;
"S \NAC"
BN"12"138;
%"TAP"
"1","(5750,1675)","0","standard","I114";
;
CDS_LIB"standard"
BODY_TYPE"PLUMBING"
HDL_TAP"TRUE";
"B \NAC \NWC"6;
"S \NAC"
BN"10"98;
%"TAP"
"1","(5750,1525)","0","standard","I115";
;
CDS_LIB"standard"
BODY_TYPE"PLUMBING"
HDL_TAP"TRUE";
"B \NAC \NWC"6;
"S \NAC"
BN"11"136;
%"TAP"
"1","(5750,1975)","0","standard","I116";
;
CDS_LIB"standard"
BODY_TYPE"PLUMBING"
HDL_TAP"TRUE";
"B \NAC \NWC"6;
"S \NAC"
BN"8"62;
%"TAP"
"1","(5750,1825)","0","standard","I117";
;
CDS_LIB"standard"
BODY_TYPE"PLUMBING"
HDL_TAP"TRUE";
"B \NAC \NWC"6;
"S \NAC"
BN"9"100;
%"TAP"
"1","(5600,2275)","0","standard","I118";
;
CDS_LIB"standard"
BODY_TYPE"PLUMBING"
HDL_TAP"TRUE";
"B \NAC \NWC"5;
"S \NAC"
BN"7"60;
%"TAP"
"1","(5600,2425)","0","standard","I119";
;
CDS_LIB"standard"
BODY_TYPE"PLUMBING"
HDL_TAP"TRUE";
"B \NAC \NWC"5;
"S \NAC"
BN"6"101;
%"Q_RES"
"1","(3675,-450)","0","pure_quanta","I12";
;
LOCATION"R3176"
$SEC"1"
CDS_SEC"1"
PACK_TYPE"0402LF"
TOLERANCE"1%"
VALUE"1K"
WATTAGE"1/16W"
MATERIAL"CHIP"
CDS_LIB"pure_quanta"
PART_NUMBER"CS21002FB06";
"B"
$PN"2"32;
"A"
$PN"1"82;
%"TAP"
"1","(5600,2725)","0","standard","I120";
;
CDS_LIB"standard"
BODY_TYPE"PLUMBING"
HDL_TAP"TRUE";
"B \NAC \NWC"5;
"S \NAC"
BN"4"105;
%"TAP"
"1","(5600,2575)","0","standard","I121";
;
CDS_LIB"standard"
BODY_TYPE"PLUMBING"
HDL_TAP"TRUE";
"B \NAC \NWC"5;
"S \NAC"
BN"5"103;
%"TAP"
"1","(5750,2475)","0","standard","I122";
;
CDS_LIB"standard"
BODY_TYPE"PLUMBING"
HDL_TAP"TRUE";
"B \NAC \NWC"6;
"S \NAC"
BN"6"102;
%"TAP"
"1","(5750,2325)","0","standard","I123";
;
CDS_LIB"standard"
BODY_TYPE"PLUMBING"
HDL_TAP"TRUE";
"B \NAC \NWC"6;
"S \NAC"
BN"7"59;
%"TAP"
"1","(5750,2625)","0","standard","I124";
;
CDS_LIB"standard"
BODY_TYPE"PLUMBING"
HDL_TAP"TRUE";
"B \NAC \NWC"6;
"S \NAC"
BN"5"104;
%"TAP"
"1","(5750,2775)","0","standard","I125";
;
CDS_LIB"standard"
BODY_TYPE"PLUMBING"
HDL_TAP"TRUE";
"B \NAC \NWC"6;
"S \NAC"
BN"4"106;
%"TAP"
"1","(5600,3025)","0","standard","I126";
;
CDS_LIB"standard"
BODY_TYPE"PLUMBING"
HDL_TAP"TRUE";
"B \NAC \NWC"5;
"S \NAC"
BN"3"107;
%"TAP"
"1","(5600,3175)","0","standard","I127";
;
CDS_LIB"standard"
BODY_TYPE"PLUMBING"
HDL_TAP"TRUE";
"B \NAC \NWC"5;
"S \NAC"
BN"2"108;
%"TAP"
"1","(5600,3325)","0","standard","I128";
;
CDS_LIB"standard"
BODY_TYPE"PLUMBING"
HDL_TAP"TRUE";
"B \NAC \NWC"5;
"S \NAC"
BN"1"110;
%"TAP"
"1","(5600,3475)","0","standard","I129";
;
CDS_LIB"standard"
BODY_TYPE"PLUMBING"
HDL_TAP"TRUE";
"B \NAC \NWC"5;
"S \NAC"
BN"0"57;
%"Q_CAP"
"1","(5700,-300)","0","pure_quanta","I13";
;
LOCATION"C1829"
$SEC"1"
CDS_SEC"1"
VALUE"22UF"
MATERIAL"X6S"
TOLERANCE"20%"
VOLTAGE"16V"
PACK_TYPE"C0805"
CDS_LIB"pure_quanta"
PART_NUMBER"CH6223MEA00";
"B"
$PN"2"38;
"A"
$PN"1"41;
%"TAP"
"1","(5750,3225)","0","standard","I130";
;
CDS_LIB"standard"
BODY_TYPE"PLUMBING"
HDL_TAP"TRUE";
"B \NAC \NWC"6;
"S \NAC"
BN"2"109;
%"TAP"
"1","(5750,3075)","0","standard","I131";
;
CDS_LIB"standard"
BODY_TYPE"PLUMBING"
HDL_TAP"TRUE";
"B \NAC \NWC"6;
"S \NAC"
BN"3"133;
%"TAP"
"1","(5750,3525)","0","standard","I132";
;
CDS_LIB"standard"
BODY_TYPE"PLUMBING"
HDL_TAP"TRUE";
"B \NAC \NWC"6;
"S \NAC"
BN"0"30;
%"TAP"
"1","(5750,3375)","0","standard","I133";
;
CDS_LIB"standard"
BODY_TYPE"PLUMBING"
HDL_TAP"TRUE";
"B \NAC \NWC"6;
"S \NAC"
BN"1"56;
%"Q_RES"
"1","(6850,725)","0","pure_quanta","I135";
;
LOCATION"R3178"
$SEC"1"
CDS_SEC"1"
PACK_TYPE"0402LF"
VALUE"0"
TOLERANCE"5%"
CDS_LIB"pure_quanta"
WATTAGE"1/16W"
MATERIAL"CHIP"
PART_NUMBER"CS00002JB13";
"B"
$PN"2"64;
"A"
$PN"1"67;
%"Q_RES"
"1","(6850,775)","0","pure_quanta","I136";
;
LOCATION"R3177"
$SEC"1"
CDS_SEC"1"
VALUE"0"
PACK_TYPE"0402LF"
TOLERANCE"5%"
WATTAGE"1/16W"
MATERIAL"CHIP"
CDS_LIB"pure_quanta"
PART_NUMBER"CS00002JB13";
"B"
$PN"2"63;
"A"
$PN"1"66;
%"UNIVERSAL_POWER"
"1","(7900,50)","0","pure_quanta_power","I137";
;
HDL_POWER"P3V3_OCP_V3_2"
CDS_LIB"pure_quanta_power";
"A"40;
%"Q_CAP"
"1","(5975,-300)","0","pure_quanta","I14";
;
LOCATION"C1830"
$SEC"1"
CDS_SEC"1"
PACK_TYPE"C0805"
MATERIAL"X6S"
TOLERANCE"20%"
VOLTAGE"16V"
VALUE"22UF"
CDS_LIB"pure_quanta"
PART_NUMBER"CH6223MEA00";
"B"
$PN"2"38;
"A"
$PN"1"41;
%"Q_CAP"
"1","(6375,-300)","0","pure_quanta","I15";
;
LOCATION"C1831"
$SEC"1"
CDS_SEC"1"
PACK_TYPE"0402"
VOLTAGE"25V"
MATERIAL"X7R"
TOLERANCE"10%"
VALUE"0.1UF"
CDS_LIB"pure_quanta"
PART_NUMBER"CH4104K1B00";
"B"
$PN"2"38;
"A"
$PN"1"41;
%"Q_RES"
"2","(7950,3625)","0","pure_quanta","I150";
;
LOCATION"R3180"
$SEC"1"
CDS_SEC"1"
PACK_TYPE"0402LF"
WATTAGE"1/16W"
MATERIAL"CHIP"
VALUE"0"
TOLERANCE"5%"
CDS_LIB"pure_quanta"
PART_NUMBER"CS00002JB13";
"A"
$PN"1"24;
"B"
$PN"2"2;
%"UNIVERSAL_GND"
"1","(7950,3350)","0","pure_quanta_power","I151";
;
ROOM"IO_SLOT"
CDS_LIB"pure_quanta_power"
HDL_POWER"GND";
"A"2;
%"Q_CAP"
"1","(6650,-300)","0","pure_quanta","I16";
;
LOCATION"C1832"
$SEC"1"
CDS_SEC"1"
VALUE"0.1UF"
MATERIAL"X7R"
PACK_TYPE"0402"
VOLTAGE"25V"
TOLERANCE"10%"
CDS_LIB"pure_quanta"
PART_NUMBER"CH4104K1B00";
"B"
$PN"2"38;
"A"
$PN"1"41;
%"TAP"
"1","(3100,1175)","2","standard","I166";
;
CDS_LIB"standard"
BODY_TYPE"PLUMBING"
HDL_TAP"TRUE";
"B \NAC \NWC"7;
"S \NAC"
BN"13"90;
%"TAP"
"1","(3250,1225)","2","standard","I167";
;
CDS_LIB"standard"
BODY_TYPE"PLUMBING"
HDL_TAP"TRUE";
"B \NAC \NWC"8;
"S \NAC"
BN"13"91;
%"SCONN168_ME1016810202011"
"1","(4475,2750)","0","pure_quanta","I168";
;
LOCATION"J35"
$SEC"1"
CDS_SEC"1"
VALUE"SCONN168_ME1016810202011"
PART_TYPE"SMLF"
MATERIAL"IO"
NEEDS_NO_SIZE"TRUE"
CDS_LMAN_SYM_OUTLINE"-500,2475,500,-2475"
CDS_LIB"pure_quanta"
PART_NUMBER"DFHSG8FR011";
"G5"
$PN"G5"18;
"G4"
$PN"G4"18;
"G3"
$PN"G3"18;
"G2"
$PN"G2"18;
"G1"
$PN"G1"18;
"PRSNTB3# \B"
$PN"B70"69;
"RFU1_NC_B69"
$PN"B69"70;
"RFU1_NC_B68"
$PN"B68"71;
"GND_B67"
$PN"B67"34;
"PETP15"
$PN"B66"86;
"PETN15"
$PN"B65"87;
"GND_B64"
$PN"B64"34;
"PETP14"
$PN"B63"88;
"PETN14"
$PN"B62"89;
"GND_B61"
$PN"B61"34;
"PETP13"
$PN"B60"90;
"PETN13"
$PN"B59"91;
"GND_B58"
$PN"B58"34;
"PETP12"
$PN"B57"92;
"PWRBRK0# \B"
$PN"A70"65;
"USB_DATP"
$PN"A69"67;
"USB_DATN"
$PN"A68"66;
"GND_A67"
$PN"A67"18;
"PERP15"
$PN"A66"137;
"PERN15"
$PN"A65"135;
"GND_A64"
$PN"A64"18;
"PERP14"
$PN"A63"140;
"PERN14"
$PN"A62"93;
"GND_A61"
$PN"A61"18;
"PERP13"
$PN"A60"94;
"PERN13"
$PN"A59"95;
"GND_A58"
$PN"A58"18;
"PERP12"
$PN"A57"141;
"PERN12"
$PN"A56"138;
"GND_A55"
$PN"A55"18;
"PERP11"
$PN"A54"96;
"PERN11"
$PN"A53"136;
"GND_A52"
$PN"A52"18;
"PERP10"
$PN"A51"97;
"PERN10"
$PN"A50"98;
"GND_A49"
$PN"A49"18;
"PERP9"
$PN"A48"99;
"PERN9"
$PN"A47"100;
"GND_A46"
$PN"A46"18;
"PERP8"
$PN"A45"61;
"PERN8"
$PN"A44"62;
"GND_A43"
$PN"A43"18;
"PRSNTB1# \B"
$PN"A42"58;
"GND_A41"
$PN"A41"18;
"PERP7"
$PN"A40"60;
"PERN7"
$PN"A39"59;
"GND_A38"
$PN"A38"18;
"PERP6"
$PN"A37"101;
"PERN6"
$PN"A36"102;
"GND_A35"
$PN"A35"18;
"PERP5"
$PN"A34"103;
"PERN5"
$PN"A33"104;
"GND_A32"
$PN"A32"18;
"PERP4"
$PN"A31"105;
"PERN4"
$PN"A30"106;
"GND_A29"
$PN"A29"18;
"GND_A28"
$PN"A28"18;
"PERP3"
$PN"A27"107;
"PERN3"
$PN"A26"133;
"GND_A25"
$PN"A25"18;
"PERP2"
$PN"A24"108;
"PERN2"
$PN"A23"109;
"GND_A22"
$PN"A22"18;
"PERP1"
$PN"A21"110;
"PERN1"
$PN"A20"56;
"GND_A19"
$PN"A19"18;
"PERP0"
$PN"A18"57;
"PERN0"
$PN"A17"30;
"GND_A16"
$PN"A16"18;
"REFCLKP1"
$PN"A15"31;
"REFCLKN1"
$PN"A14"28;
"GND_A13"
$PN"A13"18;
"PRSNTB2# \B"
$PN"A12"27;
"PERST1# \B"
$PN"A11"26;
"PRSNTA# \B"
$PN"A10"24;
"SMRST# \B"
$PN"A9"25;
"SMDAT"
$PN"A8"148;
"SMCLK"
$PN"A7"22;
"GND_A6"
$PN"A6"18;
"GND_A5"
$PN"A5"18;
"GND_A4"
$PN"A4"18;
"GND_A3"
$PN"A3"18;
"GND_A2"
$PN"A2"18;
"GND_A1"
$PN"A1"18;
"RBT_CLK_IN"
$PN"OA14"21;
"GND_OA13"
$PN"OA13"18;
"REFCLKP3"
$PN"OA12"20;
"REFCLKN3"
$PN"OA11"19;
"GND_OA10"
$PN"OA10"18;
"RBT_TXD0"
$PN"OA9"12;
"RBT_TXD1"
$PN"OA8"13;
"RBT_TX_EN"
$PN"OA7"14;
"SLOT_ID1"
$PN"OA6"15;
"RBT_ARB_OUT"
$PN"OA5"16;
"RBT_ARB_IN"
$PN"OA4"139;
"WAKE# \B"
$PN"OA3"74;
"PERST3# \B"
$PN"OA2"111;
"PERST2# \B"
$PN"OA1"55;
"PETN12"
$PN"B56"112;
"GND_B55"
$PN"B55"34;
"PETP11"
$PN"B54"113;
"PETN11"
$PN"B53"114;
"GND_B52"
$PN"B52"34;
"PETP10"
$PN"B51"115;
"PETN10"
$PN"B50"116;
"GND_B49"
$PN"B49"34;
"PETP9"
$PN"B48"117;
"PETN9"
$PN"B47"118;
"GND_B46"
$PN"B46"34;
"PETP8"
$PN"B45"119;
"PETN8"
$PN"B44"120;
"GND_B43"
$PN"B43"34;
"PRSNTB0# \B"
$PN"B42"72;
"GND_B41"
$PN"B41"34;
"PETP7"
$PN"B40"121;
"PETN7"
$PN"B39"122;
"GND_B38"
$PN"B38"34;
"PETP6"
$PN"B37"123;
"PETN6"
$PN"B36"124;
"GND_B35"
$PN"B35"34;
"PETP5"
$PN"B34"125;
"PETN5"
$PN"B33"126;
"GND_B32"
$PN"B32"34;
"PETP4"
$PN"B31"127;
"PETN4"
$PN"B30"128;
"GND_B29"
$PN"B29"34;
"GND_B28"
$PN"B28"34;
"PETP3"
$PN"B27"129;
"PETN3"
$PN"B26"130;
"GND_B25"
$PN"B25"34;
"PETP2"
$PN"B24"131;
"PETN2"
$PN"B23"76;
"GND_B22"
$PN"B22"34;
"PETP1"
$PN"B21"77;
"PETN1"
$PN"B20"78;
"GND_B19"
$PN"B19"34;
"PETP0"
$PN"B18"79;
"PETN0"
$PN"B17"75;
"GND_B16"
$PN"B16"34;
"REFCLKP0"
$PN"B15"54;
"REFCLKN0"
$PN"B14"53;
"GND_B13"
$PN"B13"34;
"AUX_PWR_EN"
$PN"B12"52;
"+3.3V_EDGE"
$PN"B11"4;
"PERST0# \B"
$PN"B10"50;
"BIF2# \B"
$PN"B9"147;
"BIF1# \B"
$PN"B8"45;
"BIF0# \B"
$PN"B7"51;
"+12V_EDGE_B6"
$PN"B6"33;
"+12V_EDGE_B5"
$PN"B5"33;
"+12V_EDGE_B4"
$PN"B4"33;
"+12V_EDGE_B3"
$PN"B3"33;
"+12V_EDGE_B2"
$PN"B2"33;
"+12V_EDGE_B1"
$PN"B1"33;
"RBT_CRS_DV"
$PN"OB14"9;
"GND_OB13"
$PN"OB13"34;
"REFCLKP2"
$PN"OB12"10;
"REFCLKN2"
$PN"OB11"11;
"GND_OB10"
$PN"OB10"34;
"RBT_RXD0"
$PN"OB9"146;
"RBT_RXD1"
$PN"OB8"145;
"SLOT_ID0"
$PN"OB7"144;
"CLK"
$PN"OB6"143;
"DATA_OUT"
$PN"OB5"132;
"DATA_IN"
$PN"OB4"42;
"LD# \B"
$PN"OB3"43;
"MAIN_PWR_EN"
$PN"OB2"44;
"NIC_PWR_GOOD"
$PN"OB1"17;
%"UNIVERSAL_GND"
"1","(4200,-750)","0","pure_quanta_power","I169";
;
CDS_LIB"pure_quanta_power"
HDL_POWER"GND";
"A"39;
%"Q_CAP"
"1","(6925,-300)","0","pure_quanta","I17";
;
LOCATION"C1833"
$SEC"1"
CDS_SEC"1"
PACK_TYPE"0402"
VALUE"0.1UF"
MATERIAL"X7R"
VOLTAGE"25V"
TOLERANCE"10%"
CDS_LIB"pure_quanta"
PART_NUMBER"CH4104K1B00";
"B"
$PN"2"38;
"A"
$PN"1"41;
%"Q_RES"
"1","(6375,3975)","0","pure_quanta","I170";
;
LOCATION"R3229"
SEC"1"
PACK_TYPE"0402LF"
WATTAGE"1/16W"
VALUE"200"
TOLERANCE"1%"
MATERIAL"CHIP"
CDS_LIB"pure_quanta"
SEC_TYPE"0402LF"
PART_NUMBER"CS12002FB06";
"B"
$PN"2"29;
"A"
$PN"1"148;
%"Q_RES"
"1","(6375,4025)","0","pure_quanta","I171";
;
LOCATION"R3228"
SEC"1"
PACK_TYPE"0402LF"
WATTAGE"1/16W"
MATERIAL"CHIP"
VALUE"200"
TOLERANCE"1%"
SEC_TYPE"0402LF"
CDS_LIB"pure_quanta"
PART_NUMBER"CS12002FB06";
"B"
$PN"2"23;
"A"
$PN"1"22;
%"Q_CAP"
"1","(7150,-300)","0","pure_quanta","I18";
;
LOCATION"C1839"
$SEC"1"
CDS_SEC"1"
VALUE"0.1UF"
PACK_TYPE"0402"
TOLERANCE"10%"
MATERIAL"X7R"
VOLTAGE"25V"
CDS_LIB"pure_quanta"
PART_NUMBER"CH4104K1B00";
"B"
$PN"2"38;
"A"
$PN"1"41;
%"UNIVERSAL_GND"
"1","(7400,-625)","0","pure_quanta_power","I19";
;
ROOM"IO_SLOT"
CDS_LIB"pure_quanta_power"
HDL_POWER"GND";
"A"38;
%"Q_RES"
"2","(275,-225)","0","pure_quanta","I2";
;
LOCATION"R3163"
$SEC"1"
CDS_SEC"1"
WATTAGE"1/16W"
MATERIAL"EMPTY"
PACK_TYPE"0402LF"
TOLERANCE"1%"
VALUE"4.7K"
CDS_LIB"pure_quanta"
PART_NUMBER"CS24702FB06";
"A"
$PN"1"83;
"B"
$PN"2"1;
%"Q_CAP"
"1","(7400,-300)","0","pure_quanta","I20";
;
LOCATION"C1834"
$SEC"1"
CDS_SEC"1"
VOLTAGE"25V"
VALUE"0.1UF"
TOLERANCE"10%"
MATERIAL"X7R"
PACK_TYPE"0402"
CDS_LIB"pure_quanta"
PART_NUMBER"CH4104K1B00";
"B"
$PN"2"38;
"A"
$PN"1"41;
%"Q_CAP"
"1","(7900,-300)","0","pure_quanta","I21";
;
LOCATION"C1835"
$SEC"1"
CDS_SEC"1"
VOLTAGE"25V"
TOLERANCE"10%"
PACK_TYPE"0402"
MATERIAL"X7R"
VALUE"0.1UF"
CDS_LIB"pure_quanta"
PART_NUMBER"CH4104K1B00";
"B"
$PN"2"37;
"A"
$PN"1"40;
%"Q_CAP"
"1","(8150,-300)","0","pure_quanta","I22";
;
LOCATION"C1836"
$SEC"1"
CDS_SEC"1"
MATERIAL"X7R"
TOLERANCE"10%"
VALUE"0.1UF"
PACK_TYPE"0402"
VOLTAGE"25V"
CDS_LIB"pure_quanta"
PART_NUMBER"CH4104K1B00";
"B"
$PN"2"37;
"A"
$PN"1"40;
%"Q_CAP"
"1","(8425,-300)","0","pure_quanta","I23";
;
LOCATION"C1837"
$SEC"1"
CDS_SEC"1"
PACK_TYPE"0402"
MATERIAL"X7R"
TOLERANCE"10%"
VOLTAGE"25V"
VALUE"0.1UF"
CDS_LIB"pure_quanta"
PART_NUMBER"CH4104K1B00";
"B"
$PN"2"37;
"A"
$PN"1"40;
%"Q_CAP"
"1","(8700,-300)","0","pure_quanta","I24";
;
LOCATION"C1838"
$SEC"1"
CDS_SEC"1"
VOLTAGE"25V"
TOLERANCE"10%"
MATERIAL"X7R"
VALUE"0.1UF"
PACK_TYPE"0402"
CDS_LIB"pure_quanta"
PART_NUMBER"CH4104K1B00";
"B"
$PN"2"37;
"A"
$PN"1"40;
%"UNIVERSAL_GND"
"1","(8700,-625)","0","pure_quanta_power","I25";
;
ROOM"IO_SLOT"
CDS_LIB"pure_quanta_power"
HDL_POWER"GND";
"A"37;
%"Q_RES"
"2","(275,300)","0","pure_quanta","I26";
;
LOCATION"R3162"
$SEC"1"
CDS_SEC"1"
WATTAGE"1/16W"
PACK_TYPE"0402LF"
TOLERANCE"1%"
MATERIAL"CHIP"
VALUE"4.7K"
CDS_LIB"pure_quanta"
PART_NUMBER"CS24702FB06";
"A"
$PN"1"36;
"B"
$PN"2"83;
%"UNIVERSAL_POWER"
"1","(275,600)","0","pure_quanta_power","I27";
;
HDL_POWER"P3V3_OCP_V3_2"
CDS_LIB"pure_quanta_power";
"A"36;
%"Q_RES"
"2","(750,300)","0","pure_quanta","I28";
;
LOCATION"R3166"
$SEC"1"
CDS_SEC"1"
VALUE"4.7K"
TOLERANCE"1%"
PACK_TYPE"0402LF"
MATERIAL"EMPTY"
WATTAGE"1/16W"
CDS_LIB"pure_quanta"
PART_NUMBER"CS24702FB06";
"A"
$PN"1"36;
"B"
$PN"2"84;
%"Q_RES"
"2","(750,-225)","0","pure_quanta","I3";
;
LOCATION"R3167"
$SEC"1"
CDS_SEC"1"
PACK_TYPE"0402LF"
VALUE"4.7K"
TOLERANCE"1%"
WATTAGE"1/16W"
MATERIAL"CHIP"
CDS_LIB"pure_quanta"
PART_NUMBER"CS24702FB06";
"A"
$PN"1"84;
"B"
$PN"2"3;
%"UNIVERSAL_GND"
"1","(300,2400)","0","pure_quanta_power","I31";
;
CDS_LIB"pure_quanta_power"
HDL_POWER"GND";
"A"35;
%"Q_RES"
"1","(725,2750)","0","pure_quanta","I32";
;
LOCATION"R3165"
$SEC"1"
CDS_SEC"1"
VALUE"10K"
MATERIAL"CHIP"
TOLERANCE"1%"
WATTAGE"1/16W"
PACK_TYPE"0402LF"
CDS_LIB"pure_quanta"
PART_NUMBER"CS31002FB08";
"B"
$PN"2"85;
"A"
$PN"1"35;
%"Q_RES"
"1","(775,2550)","0","pure_quanta","I33";
;
LOCATION"R8413"
$SEC"1"
CDS_SEC"1"
VALUE"100K"
TOLERANCE"1%"
MATERIAL"CHIP"
PACK_TYPE"0402LF"
WATTAGE"1/16W"
CDS_LIB"pure_quanta"
PART_NUMBER"CS41002FB09";
"B"
$PN"2"134;
"A"
$PN"1"35;
%"Q_RES"
"1","(725,2850)","0","pure_quanta","I34";
;
LOCATION"R3164"
$SEC"1"
CDS_SEC"1"
MATERIAL"CHIP"
PACK_TYPE"0402LF"
VALUE"10K"
TOLERANCE"1%"
WATTAGE"1/16W"
CDS_LIB"pure_quanta"
PART_NUMBER"CS31002FB08";
"B"
$PN"2"73;
"A"
$PN"1"35;
%"UNIVERSAL_GND"
"1","(750,-450)","0","pure_quanta_power","I4";
;
ROOM"IO_SLOT"
CDS_LIB"pure_quanta_power"
HDL_POWER"GND";
"A"3;
%"Q_RES"
"1","(1950,3775)","0","pure_quanta","I42";
;
LOCATION"R3172"
$SEC"1"
CDS_SEC"1"
PACK_TYPE"0402LF"
TOLERANCE"5%"
VALUE"0"
WATTAGE"1/16W"
MATERIAL"CHIP"
CDS_LIB"pure_quanta"
PART_NUMBER"CS00002JB13";
"B"
$PN"2"52;
"A"
$PN"1"142;
%"Q_RES"
"1","(1950,4025)","0","pure_quanta","I43";
;
LOCATION"R3169"
$SEC"1"
CDS_SEC"1"
TOLERANCE"5%"
PACK_TYPE"0402LF"
MATERIAL"CHIP"
VALUE"0"
WATTAGE"1/16W"
CDS_LIB"pure_quanta"
PART_NUMBER"CS00002JB13";
"B"
$PN"2"51;
"A"
$PN"1"47;
%"Q_RES"
"1","(1950,3975)","0","pure_quanta","I44";
;
LOCATION"R3170"
$SEC"1"
CDS_SEC"1"
VALUE"0"
TOLERANCE"5%"
PACK_TYPE"0402LF"
WATTAGE"1/16W"
MATERIAL"CHIP"
CDS_LIB"pure_quanta"
PART_NUMBER"CS00002JB13";
"B"
$PN"2"45;
"A"
$PN"1"48;
%"Q_RES"
"1","(1950,3925)","0","pure_quanta","I45";
;
LOCATION"R3171"
$SEC"1"
CDS_SEC"1"
VALUE"0"
TOLERANCE"5%"
PACK_TYPE"0402LF"
CDS_LIB"pure_quanta"
MATERIAL"CHIP"
WATTAGE"1/16W"
PART_NUMBER"CS00002JB13";
"B"
$PN"2"147;
"A"
$PN"1"49;
%"TAP"
"1","(3100,875)","2","standard","I47";
;
CDS_LIB"standard"
BODY_TYPE"PLUMBING"
HDL_TAP"TRUE";
"B \NAC \NWC"7;
"S \NAC"
BN"15"86;
%"TAP"
"1","(3250,925)","2","standard","I48";
;
CDS_LIB"standard"
BODY_TYPE"PLUMBING"
HDL_TAP"TRUE";
"B \NAC \NWC"8;
"S \NAC"
BN"15"87;
%"UNIVERSAL_GND"
"1","(3650,175)","0","pure_quanta_power","I49";
;
CDS_LIB"pure_quanta_power"
HDL_POWER"GND";
"A"34;
%"TAP"
"1","(3100,1025)","2","standard","I50";
;
CDS_LIB"standard"
BODY_TYPE"PLUMBING"
HDL_TAP"TRUE";
"B \NAC \NWC"7;
"S \NAC"
BN"14"88;
%"TAP"
"1","(3250,1075)","2","standard","I51";
;
CDS_LIB"standard"
BODY_TYPE"PLUMBING"
HDL_TAP"TRUE";
"B \NAC \NWC"8;
"S \NAC"
BN"14"89;
%"TAP"
"1","(3100,1325)","2","standard","I52";
;
CDS_LIB"standard"
BODY_TYPE"PLUMBING"
HDL_TAP"TRUE";
"B \NAC \NWC"7;
"S \NAC"
BN"12"92;
%"TAP"
"1","(3100,1475)","2","standard","I53";
;
CDS_LIB"standard"
BODY_TYPE"PLUMBING"
HDL_TAP"TRUE";
"B \NAC \NWC"7;
"S \NAC"
BN"11"113;
%"TAP"
"1","(3250,1375)","2","standard","I54";
;
CDS_LIB"standard"
BODY_TYPE"PLUMBING"
HDL_TAP"TRUE";
"B \NAC \NWC"8;
"S \NAC"
BN"12"112;
%"TAP"
"1","(3100,1625)","2","standard","I55";
;
CDS_LIB"standard"
BODY_TYPE"PLUMBING"
HDL_TAP"TRUE";
"B \NAC \NWC"7;
"S \NAC"
BN"10"115;
%"TAP"
"1","(3250,1525)","2","standard","I56";
;
CDS_LIB"standard"
BODY_TYPE"PLUMBING"
HDL_TAP"TRUE";
"B \NAC \NWC"8;
"S \NAC"
BN"11"114;
%"TAP"
"1","(3250,1675)","2","standard","I57";
;
CDS_LIB"standard"
BODY_TYPE"PLUMBING"
HDL_TAP"TRUE";
"B \NAC \NWC"8;
"S \NAC"
BN"10"116;
%"TAP"
"1","(3100,1775)","2","standard","I58";
;
CDS_LIB"standard"
BODY_TYPE"PLUMBING"
HDL_TAP"TRUE";
"B \NAC \NWC"7;
"S \NAC"
BN"9"117;
%"TAP"
"1","(3100,1925)","2","standard","I59";
;
CDS_LIB"standard"
BODY_TYPE"PLUMBING"
HDL_TAP"TRUE";
"B \NAC \NWC"7;
"S \NAC"
BN"8"119;
%"TAP"
"1","(3250,1975)","2","standard","I60";
;
CDS_LIB"standard"
BODY_TYPE"PLUMBING"
HDL_TAP"TRUE";
"B \NAC \NWC"8;
"S \NAC"
BN"8"120;
%"TAP"
"1","(3250,1825)","2","standard","I61";
;
CDS_LIB"standard"
BODY_TYPE"PLUMBING"
HDL_TAP"TRUE";
"B \NAC \NWC"8;
"S \NAC"
BN"9"118;
%"TAP"
"1","(3100,2275)","2","standard","I68";
;
CDS_LIB"standard"
BODY_TYPE"PLUMBING"
HDL_TAP"TRUE";
"B \NAC \NWC"7;
"S \NAC"
BN"7"121;
%"TAP"
"1","(3100,2425)","2","standard","I69";
;
CDS_LIB"standard"
BODY_TYPE"PLUMBING"
HDL_TAP"TRUE";
"B \NAC \NWC"7;
"S \NAC"
BN"6"123;
%"TAP"
"1","(3250,2325)","2","standard","I70";
;
CDS_LIB"standard"
BODY_TYPE"PLUMBING"
HDL_TAP"TRUE";
"B \NAC \NWC"8;
"S \NAC"
BN"7"122;
%"TAP"
"1","(3250,2475)","2","standard","I71";
;
CDS_LIB"standard"
BODY_TYPE"PLUMBING"
HDL_TAP"TRUE";
"B \NAC \NWC"8;
"S \NAC"
BN"6"124;
%"TAP"
"1","(3100,2575)","2","standard","I72";
;
CDS_LIB"standard"
BODY_TYPE"PLUMBING"
HDL_TAP"TRUE";
"B \NAC \NWC"7;
"S \NAC"
BN"5"125;
%"TAP"
"1","(3100,2725)","2","standard","I73";
;
CDS_LIB"standard"
BODY_TYPE"PLUMBING"
HDL_TAP"TRUE";
"B \NAC \NWC"7;
"S \NAC"
BN"4"127;
%"TAP"
"1","(3250,2625)","2","standard","I74";
;
CDS_LIB"standard"
BODY_TYPE"PLUMBING"
HDL_TAP"TRUE";
"B \NAC \NWC"8;
"S \NAC"
BN"5"126;
%"TAP"
"1","(3250,2775)","2","standard","I75";
;
CDS_LIB"standard"
BODY_TYPE"PLUMBING"
HDL_TAP"TRUE";
"B \NAC \NWC"8;
"S \NAC"
BN"4"128;
%"TAP"
"1","(3100,3025)","2","standard","I76";
;
CDS_LIB"standard"
BODY_TYPE"PLUMBING"
HDL_TAP"TRUE";
"B \NAC \NWC"7;
"S \NAC"
BN"3"129;
%"TAP"
"1","(3100,3175)","2","standard","I77";
;
CDS_LIB"standard"
BODY_TYPE"PLUMBING"
HDL_TAP"TRUE";
"B \NAC \NWC"7;
"S \NAC"
BN"2"131;
%"TAP"
"1","(3250,3075)","2","standard","I78";
;
CDS_LIB"standard"
BODY_TYPE"PLUMBING"
HDL_TAP"TRUE";
"B \NAC \NWC"8;
"S \NAC"
BN"3"130;
%"TAP"
"1","(3250,3225)","2","standard","I79";
;
CDS_LIB"standard"
BODY_TYPE"PLUMBING"
HDL_TAP"TRUE";
"B \NAC \NWC"8;
"S \NAC"
BN"2"76;
%"TAP"
"1","(3100,3325)","2","standard","I80";
;
CDS_LIB"standard"
BODY_TYPE"PLUMBING"
HDL_TAP"TRUE";
"B \NAC \NWC"7;
"S \NAC"
BN"1"77;
%"TAP"
"1","(3100,3475)","2","standard","I81";
;
CDS_LIB"standard"
BODY_TYPE"PLUMBING"
HDL_TAP"TRUE";
"B \NAC \NWC"7;
"S \NAC"
BN"0"79;
%"TAP"
"1","(3250,3525)","2","standard","I82";
;
CDS_LIB"standard"
BODY_TYPE"PLUMBING"
HDL_TAP"TRUE";
"B \NAC \NWC"8;
"S \NAC"
BN"0"75;
%"TAP"
"1","(3250,3375)","2","standard","I83";
;
CDS_LIB"standard"
BODY_TYPE"PLUMBING"
HDL_TAP"TRUE";
"B \NAC \NWC"8;
"S \NAC"
BN"1"78;
%"Q_RES"
"1","(1950,5075)","0","pure_quanta","I86";
;
LOCATION"R3168"
$SEC"1"
CDS_SEC"1"
TOLERANCE"5%"
VALUE"0"
PACK_TYPE"0402LF"
MATERIAL"CHIP"
WATTAGE"1/16W"
CDS_LIB"pure_quanta"
PART_NUMBER"CS00002JB13";
"B"
$PN"2"44;
"A"
$PN"1"46;
%"Q_RES"
"1","(3650,-275)","0","pure_quanta","I9";
;
LOCATION"R3174"
$SEC"1"
CDS_SEC"1"
TOLERANCE"1%"
VALUE"10K"
MATERIAL"CHIP"
WATTAGE"1/16W"
PACK_TYPE"0402LF"
CDS_LIB"pure_quanta"
PART_NUMBER"CS31002FB08";
"B"
$PN"2"32;
"A"
$PN"1"80;
%"UNIVERSAL_POWER"
"1","(2550,4225)","0","pure_quanta_power","I97";
;
HDL_POWER"P3V3_OCP_V3_2"
CDS_LIB"pure_quanta_power";
"A"4;
%"UNIVERSAL_POWER"
"1","(3525,5450)","0","pure_quanta_power","I98";
;
HDL_POWER"P12V_OCP_V3_2_R"
CDS_LIB"pure_quanta_power";
"A"33;
%"UNIVERSAL_POWER"
"1","(4200,50)","0","pure_quanta_power","I99";
;
HDL_POWER"P3V3_OCP_V3_2"
CDS_LIB"pure_quanta_power";
"A"32;
END.
